# BASEBOARD_FAB2 (Tioga Pass) — schematic netlist excerpt (pin names and nets, part order shuffled) for the footprints in the layout excerpt that follows; sources: Cadence DE-HDL packaged netlist, KiCad conversion of Wiwynn_Tioga_Pass_MB.brd

J6U2  SCONN288_H44441003  SCONN  pkg PIP  page 48
  \12v\(1)  = P12V_NVDIMM_ABC
  VSS(93)  = GND
  DQ(4)  = M_C_DQ<4>
  VSS(92)  = GND
  DQ(0)  = M_C_DQ<0>
  VSS(91)  = GND
  DQS9P  = M_C_DQS_DP<9>
  DQS9N  = M_C_DQS_DN<9>
  VSS(90)  = GND
  DQ(6)  = M_C_DQ<6>
  VSS(89)  = GND
  DQ(2)  = M_C_DQ<2>
  VSS(88)  = GND
  DQ(12)  = M_C_DQ<12>
  VSS(87)  = GND
  DQ(8)  = M_C_DQ<8>
  VSS(86)  = GND
  DQS10P  = M_C_DQS_DP<10>
  DQS10N  = M_C_DQS_DN<10>
  VSS(85)  = GND
  DQ(14)  = M_C_DQ<14>
  VSS(84)  = GND
  DQ(10)  = M_C_DQ<10>
  VSS(83)  = GND
  DQ(20)  = M_C_DQ<20>
  VSS(82)  = GND
  DQ(16)  = M_C_DQ<16>
  VSS(81)  = GND
  DQS11P  = M_C_DQS_DP<11>
  DQS11N  = M_C_DQS_DN<11>
  VSS(80)  = GND
  DQ(22)  = M_C_DQ<22>
  VSS(79)  = GND
  DQ(18)  = M_C_DQ<18>
  VSS(78)  = GND
  DQ(28)  = M_C_DQ<28>
  VSS(77)  = GND
  DQ(24)  = M_C_DQ<24>
  VSS(76)  = GND
  DQS12P  = M_C_DQS_DP<12>
  DQS12N  = M_C_DQS_DN<12>
  VSS(75)  = GND
  DQ(30)  = M_C_DQ<30>
  VSS(74)  = GND
  DQ(26)  = M_C_DQ<26>
  VSS(73)  = GND
  CB(4)  = M_C_ECC<4>
  VSS(72)  = GND
  CB(0)  = M_C_ECC<0>
  VSS(71)  = GND
  DQS17P  = M_C_DQS_DP<17>
  DQS17N  = M_C_DQS_DN<17>
  VSS(70)  = GND
  CB(6)  = M_C_ECC<6>
  VSS(69)  = GND
  CB(2)  = M_C_ECC<2>
  VSS(68)  = GND
  RESET_N  = M_ABC_RST_N
  VDD(25)  = PVDDQ_ABC
  CKE(0)  = M_C_CKE<2>
  VDD(24)  = PVDDQ_ABC
  ACT_N  = M_C_ACT_N
  BG(0)  = M_C_BG<0>
  VDD(23)  = PVDDQ_ABC
  A12  = M_C_MA<12>
  A9  = M_C_MA<9>
  VDD(22)  = PVDDQ_ABC
  A8  = M_C_MA<8>
  A6  = M_C_MA<6>
  VDD(21)  = PVDDQ_ABC
  A3  = M_C_MA<3>
  A1  = M_C_MA<1>
  VDD(20)  = PVDDQ_ABC
  CK0P  = M_C_CLK_DP<2>
  CK0N  = M_C_CLK_DN<2>
  VDD(19)  = PVDDQ_ABC
  VTT(1)  = PVTT_ABC
  EVENT_N  = FM_DIMM_EVENT_COD_N
  A0  = M_C_MA<0>
  VDD(18)  = PVDDQ_ABC
  BA(0)  = M_C_BA<0>
  A16_RAS_N  = M_C_MA<16>
  VDD(17)  = PVDDQ_ABC
  S0_N  = M_C_CS_N<4>
  VDD(16)  = PVDDQ_ABC
  A15_CAS_N  = M_C_MA<15>
  ODT(0)  = M_C_ODT<2>
  VDD(15)  = PVDDQ_ABC
  S1_N  = M_C_CS_N<5>
  VDD(14)  = PVDDQ_ABC
  ODT(1)  = M_C_ODT<3>
  VDD(13)  = PVDDQ_ABC
  S2_N_C(0)  = M_C_CS_N<6>
  VSS(67)  = GND
  DQ(36)  = M_C_DQ<36>
  VSS(66)  = GND
  DQ(32)  = M_C_DQ<32>
  VSS(65)  = GND
  DQS13P  = M_C_DQS_DP<13>
  DQS13N  = M_C_DQS_DN<13>
  VSS(64)  = GND
  DQ(38)  = M_C_DQ<38>
  VSS(63)  = GND
  DQ(34)  = M_C_DQ<34>
  VSS(62)  = GND
  DQ(44)  = M_C_DQ<44>
  VSS(61)  = GND
  DQ(40)  = M_C_DQ<40>
  VSS(60)  = GND
  DQS14P  = M_C_DQS_DP<14>
  DQS14N  = M_C_DQS_DN<14>
  VSS(59)  = GND
  DQ(46)  = M_C_DQ<46>
  VSS(58)  = GND
  DQ(42)  = M_C_DQ<42>
  VSS(57)  = GND
  DQ(52)  = M_C_DQ<52>
  VSS(56)  = GND
  DQ(48)  = M_C_DQ<48>
  VSS(55)  = GND
  DQS15P  = M_C_DQS_DP<15>
  DQS15N  = M_C_DQS_DN<15>
  VSS(54)  = GND
  DQ(54)  = M_C_DQ<54>
  VSS(53)  = GND
  DQ(50)  = M_C_DQ<50>
  VSS(52)  = GND
  DQ(60)  = M_C_DQ<60>
  VSS(51)  = GND
  DQ(56)  = M_C_DQ<56>
  VSS(50)  = GND
  DQS16P  = M_C_DQS_DP<16>
  DQS16N  = M_C_DQS_DN<16>
  VSS(49)  = GND
  DQ(62)  = M_C_DQ<62>
  VSS(48)  = GND
  DQ(58)  = M_C_DQ<58>
  VSS(47)  = GND
  SA(0)  = PVPP_ABC
  SA(1)  = GND
  SCL  = SMB_DDR_ABC_VPP_SCL
  VPP(4)  = PVPP_ABC
  VPP(3)  = PVPP_ABC
  RFU(2)  = TP_CH_C_DIMM_C1_RFU_2
  \12v\(0)  = P12V_NVDIMM_ABC
  VREFCA  = M_C_VREF
  VSS(46)  = GND
  DQ(5)  = M_C_DQ<5>
  VSS(45)  = GND
  DQ(1)  = M_C_DQ<1>
  VSS(44)  = GND
  DQS0N  = M_C_DQS_DN<0>
  DQS0P  = M_C_DQS_DP<0>
  VSS(43)  = GND
  DQ(7)  = M_C_DQ<7>
  VSS(42)  = GND
  DQ(3)  = M_C_DQ<3>
  VSS(41)  = GND
  DQ(13)  = M_C_DQ<13>
  VSS(40)  = GND
  DQ(9)  = M_C_DQ<9>
  VSS(39)  = GND
  DQS1N  = M_C_DQS_DN<1>
  DQS1P  = M_C_DQS_DP<1>
  VSS(38)  = GND
  DQ(15)  = M_C_DQ<15>
  VSS(37)  = GND
  DQ(11)  = M_C_DQ<11>
  VSS(36)  = GND
  DQ(21)  = M_C_DQ<21>
  VSS(35)  = GND
  DQ(17)  = M_C_DQ<17>
  VSS(34)  = GND
  DQS2N  = M_C_DQS_DN<2>
  DQS2P  = M_C_DQS_DP<2>
  VSS(33)  = GND
  DQ(23)  = M_C_DQ<23>
  VSS(32)  = GND
  DQ(19)  = M_C_DQ<19>
  VSS(31)  = GND
  DQ(29)  = M_C_DQ<29>
  VSS(30)  = GND
  DQ(25)  = M_C_DQ<25>
  VSS(29)  = GND
  DQS3N  = M_C_DQS_DN<3>
  DQS3P  = M_C_DQS_DP<3>
  VSS(28)  = GND
  DQ(31)  = M_C_DQ<31>
  VSS(27)  = GND
  DQ(27)  = M_C_DQ<27>
  VSS(26)  = GND
  CB(5)  = M_C_ECC<5>
  VSS(25)  = GND
  CB(1)  = M_C_ECC<1>
  VSS(24)  = GND
  DQS8N  = M_C_DQS_DN<8>
  DQS8P  = M_C_DQS_DP<8>
  VSS(23)  = GND
  CB(7)  = M_C_ECC<7>
  VSS(22)  = GND
  CB(3)  = M_C_ECC<3>
  VSS(21)  = GND
  CKE(1)  = M_C_CKE<3>
  VDD(12)  = PVDDQ_ABC
  RFU(0)  = TP_CH_C_DIMM_C1_RFU_0
  VDD(11)  = PVDDQ_ABC
  BG(1)  = M_C_BG<1>
  ALERT_N  = M_C_ALERT_N
  VDD(10)  = PVDDQ_ABC
  A11  = M_C_MA<11>
  A7  = M_C_MA<7>
  VDD(9)  = PVDDQ_ABC
  A5  = M_C_MA<5>
  A4  = M_C_MA<4>
  VDD(8)  = PVDDQ_ABC
  A2  = M_C_MA<2>
  VDD(7)  = PVDDQ_ABC
  CK1P  = M_C_CLK_DP<3>
  CK1N  = M_C_CLK_DN<3>
  VDD(6)  = PVDDQ_ABC
  VTT(0)  = PVTT_ABC
  PAR  = M_C_PAR
  VDD(5)  = PVDDQ_ABC
  BA(1)  = M_C_BA<1>
  A10  = M_C_MA<10>
  VDD(4)  = PVDDQ_ABC
  RFU(1)  = TP_CH_C_DIMM_C1_RFU_1
  A14_WE_N  = M_C_MA<14>
  VDD(3)  = PVDDQ_ABC
  SAVE_N_NC  = FM_ADR_COMPLETE_ABC_N
  VDD(2)  = PVDDQ_ABC
  A13  = M_C_MA<13>
  VDD(1)  = PVDDQ_ABC
  A17  = M_C_MA<17>
  C(2)  = M_C_C<2>
  VDD(0)  = PVDDQ_ABC
  S3_N_C(1)  = M_C_CS_N<7>
  SA(2)  = PVPP_ABC
  VSS(20)  = GND
  DQ(37)  = M_C_DQ<37>
  VSS(19)  = GND
  DQ(33)  = M_C_DQ<33>
  VSS(18)  = GND
  DQS4N  = M_C_DQS_DN<4>
  DQS4P  = M_C_DQS_DP<4>
  VSS(17)  = GND
  DQ(39)  = M_C_DQ<39>
  VSS(16)  = GND
  DQ(35)  = M_C_DQ<35>
  VSS(15)  = GND
  DQ(45)  = M_C_DQ<45>
  VSS(14)  = GND
  DQ(41)  = M_C_DQ<41>
  VSS(13)  = GND
  DQS5N  = M_C_DQS_DN<5>
  DQS5P  = M_C_DQS_DP<5>
  VSS(12)  = GND
  DQ(47)  = M_C_DQ<47>
  VSS(11)  = GND
  DQ(43)  = M_C_DQ<43>
  VSS(10)  = GND
  DQ(53)  = M_C_DQ<53>
  VSS(9)  = GND
  DQ(49)  = M_C_DQ<49>
  VSS(8)  = GND
  DQS6N  = M_C_DQS_DN<6>
  DQS6P  = M_C_DQS_DP<6>
  VSS(7)  = GND
  DQ(55)  = M_C_DQ<55>
  VSS(6)  = GND
  DQ(51)  = M_C_DQ<51>
  VSS(5)  = GND
  DQ(61)  = M_C_DQ<61>
  VSS(4)  = GND
  DQ(57)  = M_C_DQ<57>
  VSS(3)  = GND
  DQS7N  = M_C_DQS_DN<7>
  DQS7P  = M_C_DQS_DP<7>
  VSS(2)  = GND
  DQ(63)  = M_C_DQ<63>
  VSS(1)  = GND
  DQ(59)  = M_C_DQ<59>
  VSS(0)  = GND
  VDDSPD  = PVPP_ABC
  SDA  = SMB_DDR_ABC_VPP_SDA
  VPP(1)  = PVPP_ABC
  VPP(0)  = PVPP_ABC
  VPP(2)  = PVPP_ABC

(kicad_pcb
	(version 20260206)
	(generator "pcbnew")
	(generator_version "10.0")
	(general
		(thickness 1.6)
		(legacy_teardrops no)
	)
	(paper "A4")
	(title_block
		(title "Wiwynn_Tioga_Pass_MB.brd")
		(comment 1 "Tioga Pass / footprint 2838 of 4770 (J6U2), pads 101-151 of 291")
	)
	(layers
		(0 "F.Cu" signal "TOP")
		(4 "In1.Cu" signal "L2GND")
		(6 "In2.Cu" signal "L3")
		(8 "In3.Cu" signal "L4GND")
		(10 "In4.Cu" signal "L5")
		(12 "In5.Cu" signal "L6GND")
		(14 "In6.Cu" signal "L7VCC")
		(16 "In7.Cu" signal "L8VCC")
		(18 "In8.Cu" signal "L9GND")
		(20 "In9.Cu" signal "L10")
		(22 "In10.Cu" signal "L11GND")
		(24 "In11.Cu" signal "L12")
		(26 "In12.Cu" signal "L13GND")
		(2 "B.Cu" signal "BOTTOM")
		(9 "F.Adhes" user "F.Adhesive")
		(11 "B.Adhes" user "B.Adhesive")
		(13 "F.Paste" user "Package Geometry/Pastemask Top")
		(15 "B.Paste" user "Package Geometry/Pastemask Bottom")
		(5 "F.SilkS" user "Ref Des/Silkscreen Top")
		(7 "B.SilkS" user "Ref Des/Silkscreen Bottom")
		(1 "F.Mask" user "Board Geometry/Soldermask Top")
		(3 "B.Mask" user "Board Geometry/Soldermask Bottom")
		(17 "Dwgs.User" user "User.Drawings")
		(19 "Cmts.User" user "User.Comments")
		(21 "Eco1.User" user "User.Eco1")
		(23 "Eco2.User" user "User.Eco2")
		(25 "Edge.Cuts" user "Board Geometry/Outline")
		(27 "Margin" user)
		(31 "F.CrtYd" user "Package Geometry/Place Bound Top")
		(29 "B.CrtYd" user "Package Geometry/Place Bound Bottom")
		(35 "F.Fab" user "Ref Des/Assembly Top")
		(33 "B.Fab" user "Ref Des/Assembly Bottom")
	)
	(footprint ""
		(layer "B.Cu")
		(at 194.700398 -5.621782 90)
		(property "Reference" "J6U2"
			(at 2.225548 39.48811 0)
			(unlocked yes)
			(layer "B.SilkS")
			(effects
				(font
					(size 0.7874 0.5842)
					(thickness 0.1524)
				)
				(justify left mirror)
			)
		)
		(property "Value" ""
			(at 0 0 90)
			(layer "B.Fab")
			(effects
				(font
					(size 1.27 1.27)
				)
				(justify mirror)
			)
		)
		(duplicate_pad_numbers_are_jumpers no)
		(pad "98" smd rect
			(at 0 87.54999 270)
			(size 1.8034 0.508)
			(layers "B.Cu" "B.Mask" "B.Paste")
			(net "GND")
		)
		(pad "99" smd rect
			(at 0 88.399874 270)
			(size 1.8034 0.508)
			(layers "B.Cu" "B.Mask" "B.Paste")
			(net "M_C_DQS_DP<13>")
		)
		(pad "100" smd rect
			(at 0 89.250012 270)
			(size 1.8034 0.508)
			(layers "B.Cu" "B.Mask" "B.Paste")
			(net "M_C_DQS_DN<13>")
		)
		(pad "101" smd rect
			(at 0 90.099896 270)
			(size 1.8034 0.508)
			(layers "B.Cu" "B.Mask" "B.Paste")
			(net "GND")
		)
		(pad "102" smd rect
			(at 0 90.950034 270)
			(size 1.8034 0.508)
			(layers "B.Cu" "B.Mask" "B.Paste")
			(net "M_C_DQ<38>")
		)
		(pad "103" smd rect
			(at 0 91.799918 270)
			(size 1.8034 0.508)
			(layers "B.Cu" "B.Mask" "B.Paste")
			(net "GND")
		)
		(pad "104" smd rect
			(at 0 92.650056 270)
			(size 1.8034 0.508)
			(layers "B.Cu" "B.Mask" "B.Paste")
			(net "M_C_DQ<34>")
		)
		(pad "105" smd rect
			(at 0 93.49994 270)
			(size 1.8034 0.508)
			(layers "B.Cu" "B.Mask" "B.Paste")
			(net "GND")
		)
		(pad "106" smd rect
			(at 0 94.350078 270)
			(size 1.8034 0.508)
			(layers "B.Cu" "B.Mask" "B.Paste")
			(net "M_C_DQ<44>")
		)
		(pad "107" smd rect
			(at 0 95.199962 270)
			(size 1.8034 0.508)
			(layers "B.Cu" "B.Mask" "B.Paste")
			(net "GND")
		)
		(pad "108" smd rect
			(at 0 96.0501 270)
			(size 1.8034 0.508)
			(layers "B.Cu" "B.Mask" "B.Paste")
			(net "M_C_DQ<40>")
		)
		(pad "109" smd rect
			(at 0 96.899984 270)
			(size 1.8034 0.508)
			(layers "B.Cu" "B.Mask" "B.Paste")
			(net "GND")
		)
		(pad "110" smd rect
			(at 0 97.750122 270)
			(size 1.8034 0.508)
			(layers "B.Cu" "B.Mask" "B.Paste")
			(net "M_C_DQS_DP<14>")
		)
		(pad "111" smd rect
			(at 0 98.600006 270)
			(size 1.8034 0.508)
			(layers "B.Cu" "B.Mask" "B.Paste")
			(net "M_C_DQS_DN<14>")
		)
		(pad "112" smd rect
			(at 0 99.44989 270)
			(size 1.8034 0.508)
			(layers "B.Cu" "B.Mask" "B.Paste")
			(net "GND")
		)
		(pad "113" smd rect
			(at 0 100.300028 270)
			(size 1.8034 0.508)
			(layers "B.Cu" "B.Mask" "B.Paste")
			(net "M_C_DQ<46>")
		)
		(pad "114" smd rect
			(at 0 101.149912 270)
			(size 1.8034 0.508)
			(layers "B.Cu" "B.Mask" "B.Paste")
			(net "GND")
		)
		(pad "115" smd rect
			(at 0 102.00005 270)
			(size 1.8034 0.508)
			(layers "B.Cu" "B.Mask" "B.Paste")
			(net "M_C_DQ<42>")
		)
		(pad "116" smd rect
			(at 0 102.849934 270)
			(size 1.8034 0.508)
			(layers "B.Cu" "B.Mask" "B.Paste")
			(net "GND")
		)
		(pad "117" smd rect
			(at 0 103.700072 270)
			(size 1.8034 0.508)
			(layers "B.Cu" "B.Mask" "B.Paste")
			(net "M_C_DQ<52>")
		)
		(pad "118" smd rect
			(at 0 104.549956 270)
			(size 1.8034 0.508)
			(layers "B.Cu" "B.Mask" "B.Paste")
			(net "GND")
		)
		(pad "119" smd rect
			(at 0 105.400094 270)
			(size 1.8034 0.508)
			(layers "B.Cu" "B.Mask" "B.Paste")
			(net "M_C_DQ<48>")
		)
		(pad "120" smd rect
			(at 0 106.249978 270)
			(size 1.8034 0.508)
			(layers "B.Cu" "B.Mask" "B.Paste")
			(net "GND")
		)
		(pad "121" smd rect
			(at 0 107.100116 270)
			(size 1.8034 0.508)
			(layers "B.Cu" "B.Mask" "B.Paste")
			(net "M_C_DQS_DP<15>")
		)
		(pad "122" smd rect
			(at 0 107.95 270)
			(size 1.8034 0.508)
			(layers "B.Cu" "B.Mask" "B.Paste")
			(net "M_C_DQS_DN<15>")
		)
		(pad "123" smd rect
			(at 0 108.799884 270)
			(size 1.8034 0.508)
			(layers "B.Cu" "B.Mask" "B.Paste")
			(net "GND")
		)
		(pad "124" smd rect
			(at 0 109.650022 270)
			(size 1.8034 0.508)
			(layers "B.Cu" "B.Mask" "B.Paste")
			(net "M_C_DQ<54>")
		)
		(pad "125" smd rect
			(at 0 110.499906 270)
			(size 1.8034 0.508)
			(layers "B.Cu" "B.Mask" "B.Paste")
			(net "GND")
		)
		(pad "126" smd rect
			(at 0 111.350044 270)
			(size 1.8034 0.508)
			(layers "B.Cu" "B.Mask" "B.Paste")
			(net "M_C_DQ<50>")
		)
		(pad "127" smd rect
			(at 0 112.199928 270)
			(size 1.8034 0.508)
			(layers "B.Cu" "B.Mask" "B.Paste")
			(net "GND")
		)
		(pad "128" smd rect
			(at 0 113.050066 270)
			(size 1.8034 0.508)
			(layers "B.Cu" "B.Mask" "B.Paste")
			(net "M_C_DQ<60>")
		)
		(pad "129" smd rect
			(at 0 113.89995 270)
			(size 1.8034 0.508)
			(layers "B.Cu" "B.Mask" "B.Paste")
			(net "GND")
		)
		(pad "130" smd rect
			(at 0 114.750088 270)
			(size 1.8034 0.508)
			(layers "B.Cu" "B.Mask" "B.Paste")
			(net "M_C_DQ<56>")
		)
		(pad "131" smd rect
			(at 0 115.599972 270)
			(size 1.8034 0.508)
			(layers "B.Cu" "B.Mask" "B.Paste")
			(net "GND")
		)
		(pad "132" smd rect
			(at 0 116.45011 270)
			(size 1.8034 0.508)
			(layers "B.Cu" "B.Mask" "B.Paste")
			(net "M_C_DQS_DP<16>")
		)
		(pad "133" smd rect
			(at 0 117.299994 270)
			(size 1.8034 0.508)
			(layers "B.Cu" "B.Mask" "B.Paste")
			(net "M_C_DQS_DN<16>")
		)
		(pad "134" smd rect
			(at 0 118.149878 270)
			(size 1.8034 0.508)
			(layers "B.Cu" "B.Mask" "B.Paste")
			(net "GND")
		)
		(pad "135" smd rect
			(at 0 119.000016 270)
			(size 1.8034 0.508)
			(layers "B.Cu" "B.Mask" "B.Paste")
			(net "M_C_DQ<62>")
		)
		(pad "136" smd rect
			(at 0 119.8499 270)
			(size 1.8034 0.508)
			(layers "B.Cu" "B.Mask" "B.Paste")
			(net "GND")
		)
		(pad "137" smd rect
			(at 0 120.700038 270)
			(size 1.8034 0.508)
			(layers "B.Cu" "B.Mask" "B.Paste")
			(net "M_C_DQ<58>")
		)
		(pad "138" smd rect
			(at 0 121.549922 270)
			(size 1.8034 0.508)
			(layers "B.Cu" "B.Mask" "B.Paste")
			(net "GND")
		)
		(pad "139" smd rect
			(at 0 122.40006 270)
			(size 1.8034 0.508)
			(layers "B.Cu" "B.Mask" "B.Paste")
			(net "PVPP_ABC")
		)
		(pad "140" smd rect
			(at 0 123.249944 270)
			(size 1.8034 0.508)
			(layers "B.Cu" "B.Mask" "B.Paste")
			(net "GND")
		)
		(pad "141" smd rect
			(at 0 124.100082 270)
			(size 1.8034 0.508)
			(layers "B.Cu" "B.Mask" "B.Paste")
			(net "SMB_DDR_ABC_VPP_SCL")
		)
		(pad "142" smd rect
			(at 0 124.949966 270)
			(size 1.8034 0.508)
			(layers "B.Cu" "B.Mask" "B.Paste")
			(net "PVPP_ABC")
		)
		(pad "143" smd rect
			(at 0 125.800104 270)
			(size 1.8034 0.508)
			(layers "B.Cu" "B.Mask" "B.Paste")
			(net "PVPP_ABC")
		)
		(pad "144" smd rect
			(at 0 126.649988 270)
			(size 1.8034 0.508)
			(layers "B.Cu" "B.Mask" "B.Paste")
			(net "TP_CH_C_DIMM_C1_RFU_2")
		)
		(pad "145" smd rect
			(at -4.59994 0 270)
			(size 1.8034 0.508)
			(layers "B.Cu" "B.Mask" "B.Paste")
			(net "P12V_NVDIMM_ABC")
		)
		(pad "146" smd rect
			(at -4.59994 0.849884 270)
			(size 1.8034 0.508)
			(layers "B.Cu" "B.Mask" "B.Paste")
			(net "M_C_VREF")
		)
		(pad "147" smd rect
			(at -4.59994 1.700022 270)
			(size 1.8034 0.508)
			(layers "B.Cu" "B.Mask" "B.Paste")
			(net "GND")
		)
		(pad "148" smd rect
			(at -4.59994 2.549906 270)
			(size 1.8034 0.508)
			(layers "B.Cu" "B.Mask" "B.Paste")
			(net "M_C_DQ<5>")
		)
	)
)
